FILE_TYPE = CONNECTIVITY;
{Allegro Design Entry HDL 16.6-p007 (v16-6-112F) 10/10/2012}
"PAGE_NUMBER" = 167;
0"NC";
1"GND\g";
2"P3V3_STBY\g";
3"GND\g";
4"GND\g";
5"P3V3_STBY\g";
6"P3V3_STBY\g";
7"GND\g";
8"GND\g";
9"GND\g";
10"GND\g";
11"GND\g";
12"P3V3_STBY\g";
13"P3V3_STBY\g";
14"P3V3_STBY\g";
15"P3V3_STBY\g";
16"P3V3_STBY\g";
17"P3V3_STBY\g";
18"P3V3_STBY\g";
19"SMB_SENSOR_STBY_LVC3_SCL";
20"SMB_SENSOR_STBY_LVC3_SDA";
21"SMB_SENSOR_TMP421_1_SDA";
22"SMB_SENSOR_TMP421_1_SCL";
23"SMB_SENSOR_STBY_LVC3_SDA";
24"SMB_SENSOR_STBY_LVC3_SDA_R2";
25"SMB_SENSOR_TMP421_2_SDA";
26"SMB_SENSOR_TMP421_2_SCL";
27"PD_FRU_WP";
28"SMB_SENSOR_STBY_LVC3_SCL_R2";
29"PU_AT24C64_A2";
30"SMB_SENSOR_STBY_LVC3_SCL";
31"ISENSE_TMP421_1_DXP";
32"PD_TMP421_1_A0";
33"ISENSE_TMP421_1_DXN";
34"PU_TMP421_1_A1";
35"ISENSE_TMP421_1_BC";
36"ISENSE_TMP421_1_E";
37"ISENSE_TMP421_2_DXP";
38"ISENSE_TMP421_2_DXN";
39"PD_TMP421_2_A1";
40"PU_TMP421_2_A0";
41"ISENSE_TMP421_2_BC";
42"ISENSE_TMP421_2_E";
43"SMB_SENSOR_STBY_LVC3_SCL";
44"SMB_SENSOR_STBY_LVC3_SDA";
45"SMB_SENSOR_STBY_LVC3_SDA";
46"SMB_SENSOR_STBY_LVC3_SCL";
47"SMB_SENSOR_BMC_STBY_LVC3_SDA";
48"SMB_SENSOR_BMC_STBY_LVC3_SCL";
49"SMB_SENSOR_PCH_STBY_LVC3_SDA";
50"SMB_SENSOR_PCH_STBY_LVC3_SCL";
%"TMP421"
"1","(-4000,4450)","0","mstr_analog","I1";
;
CDS_SEC"1"
CDS_LIB"mstr_analog"
PACK_TYPE"TSSOP"
SEC_TYPE"TSSOP"
BOM_COST"SM_THERM"
SEC"1"
CDS_LOCATION"U9B4"
ROOM"TEMP_SENSORS"
PART_NUMBER"G62962-001"
LOCATION"U9B4"
MATERIAL"IC";
"VP"
$PN"8"2;
"A<0>"
$PN"4"32;
"A<1>"
$PN"3"34;
"DXP"
$PN"1"31;
"DXN"
$PN"2"33;
"GND"
$PN"5"3;
"SCL"
$PN"7"22;
"SDA"
$PN"6"21;
%"RES"
"2","(-4775,4075)","0","mstr_discrete","I10";
;
CDS_SEC"1"
ROOM"TEMP_SENSORS"
CDS_LOCATION"R9B8"
SEC"1"
SEC_TYPE"0402"
BOM_COST"SM_THERM"
CDS_LIB"mstr_discrete"
VALUE"1.00K"
TOLERANCE"1%"
LOCATION"R9B8"
PART_NUMBER"G21796-026"
WATTAGE"1/16W"
PACK_TYPE"0402"
MATERIAL"CHIP";
"A"
$PN"1"32;
"B"
$PN"2"1;
%"GND"
"1","(-4775,3850)","0","mstr_symbols","I12";
;
HDL_POWER"GND"
CDS_LIB"mstr_symbols"
VOLTAGE"0.0V"
SIZE"1B"
BODY_TYPE"PLUMBING";
"A\NAC"1;
%"P3V3_STBY"
"1","(-4350,5150)","0","mstr_symbols","I14";
;
CDS_LIB"mstr_symbols"
SIZE"1B"
VOLTAGE"3.3V"
BODY_TYPE"PLUMBING"
HDL_POWER"P3V3_STBY";
"G\NAC"2;
%"GND"
"1","(-3400,3850)","0","mstr_symbols","I15";
;
VOLTAGE"0.0V"
CDS_LIB"mstr_symbols"
SIZE"1B"
BODY_TYPE"PLUMBING"
HDL_POWER"GND";
"A\NAC"3;
%"GND"
"1","(-3225,2400)","0","mstr_symbols","I22";
;
HDL_POWER"GND"
VOLTAGE"0.0V"
SIZE"1B"
CDS_LIB"mstr_symbols"
BODY_TYPE"PLUMBING";
"A\NAC"4;
%"P3V3_STBY"
"1","(-4175,3700)","0","mstr_symbols","I23";
;
VOLTAGE"3.3V"
SIZE"1B"
CDS_LIB"mstr_symbols"
BODY_TYPE"PLUMBING"
HDL_POWER"P3V3_STBY";
"G\NAC"5;
%"CAP"
"1","(-4675,3175)","0","mstr_discrete","I24";
;
CDS_SEC"1"
SEC_TYPE"0402LF"
BOM_COST"SM_THERM"
SEC"1"
ROOM"TEMP_SENSORS"
CDS_LOCATION"C1E19"
CDS_LIB"mstr_discrete"
MATERIAL"EMPTY"
PACK_TYPE"0402LF"
LOCATION"C1E19"
VALUE"47.0PF"
TOLERANCE"5%"
VOLTAGE"50V"
PART_NUMBER"A36095-025";
"A"
$PN"1"37;
"B"
$PN"2"38;
%"RES"
"1","(-5000,3325)","0","mstr_discrete","I25";
;
CDS_SEC"1"
SEC_TYPE"0402"
BOM_COST"SM_THERM"
SEC"1"
CDS_LOCATION"R9R5"
ROOM"TEMP_SENSORS"
CDS_LIB"mstr_discrete"
PART_NUMBER"G21796-047"
PACK_TYPE"0402"
LOCATION"R9R5"
TOLERANCE"1%"
MATERIAL"CHIP"
VALUE"49.9"
WATTAGE"1/16W";
"B"
$PN"2"37;
"A"
$PN"1"42;
%"RES"
"1","(-4975,3000)","0","mstr_discrete","I26";
;
CDS_SEC"1"
SEC"1"
SEC_TYPE"0402"
BOM_COST"SM_THERM"
ROOM"TEMP_SENSORS"
CDS_LOCATION"R9R6"
CDS_LIB"mstr_discrete"
PART_NUMBER"G21796-047"
LOCATION"R9R6"
PACK_TYPE"0402"
WATTAGE"1/16W"
TOLERANCE"1%"
VALUE"49.9"
MATERIAL"CHIP";
"B"
$PN"2"38;
"A"
$PN"1"41;
%"PNP"
"3","(-5700,3150)","0","mstr_discrete","I27";
;
CDS_SEC"1"
SEC_TYPE"TO92"
BOM_COST"SM_THERM"
SEC"1"
CDS_LIB"mstr_discrete"
CDS_LOCATION"Q1E1"
ROOM"TEMP_SENSORS"
MATERIAL"IC"
LOCATION"Q1E1"
VALUE"MPS2907"
PACK_TYPE"TO92"
PART_NUMBER"G73554-001";
"B"
$PN"1"41;
"E"
$PN"2"42;
"C"
$PN"3"41;
%"P3V3_STBY"
"1","(-6400,3075)","0","mstr_symbols","I29";
;
CDS_LIB"mstr_symbols"
SIZE"1B"
BODY_TYPE"PLUMBING"
VOLTAGE"3.3V"
HDL_POWER"P3V3_STBY";
"G\NAC"6;
%"PNP"
"3","(-5775,4600)","0","mstr_discrete","I3";
;
CDS_SEC"1"
SEC"1"
BOM_COST"SM_THERM"
SEC_TYPE"TO92"
CDS_LOCATION"Q9B1"
ROOM"TEMP_SENSORS"
CDS_LIB"mstr_discrete"
LOCATION"Q9B1"
VALUE"MPS2907"
PACK_TYPE"TO92"
MATERIAL"IC"
PART_NUMBER"G73554-001";
"B"
$PN"1"35;
"E"
$PN"2"36;
"C"
$PN"3"35;
%"TMP421"
"1","(-3825,3000)","0","mstr_analog","I30";
;
CDS_SEC"1"
PACK_TYPE"TSSOP"
SEC_TYPE"TSSOP"
BOM_COST"SM_THERM"
SEC"1"
CDS_LOCATION"U1E1"
ROOM"TEMP_SENSORS"
CDS_LIB"mstr_analog"
LOCATION"U1E1"
MATERIAL"IC"
PART_NUMBER"G62962-001";
"VP"
$PN"8"5;
"A<0>"
$PN"4"40;
"A<1>"
$PN"3"39;
"DXP"
$PN"1"37;
"DXN"
$PN"2"38;
"GND"
$PN"5"4;
"SCL"
$PN"7"26;
"SDA"
$PN"6"25;
%"RES"
"1","(-5050,2850)","0","mstr_discrete","I34";
;
CDS_SEC"1"
SEC_TYPE"0402"
BOM_COST"SM_THERM"
SEC"1"
ROOM"TEMP_SENSORS"
CDS_LOCATION"R1E9"
CDS_LIB"mstr_discrete"
PACK_TYPE"0402"
PART_NUMBER"G21796-026"
LOCATION"R1E9"
TOLERANCE"1%"
MATERIAL"CHIP"
VALUE"1.00K"
WATTAGE"1/16W";
"B"
$PN"2"40;
"A"
$PN"1"6;
%"RES"
"1","(-5450,4350)","0","mstr_discrete","I35";
;
CDS_SEC"1"
BOM_COST"SM_THERM"
ROOM"TEMP_SENSORS"
SEC"1"
SEC_TYPE"0402"
CDS_LIB"mstr_discrete"
CDS_LOCATION"R9B6"
PART_NUMBER"G21796-026"
PACK_TYPE"0402"
TOLERANCE"1%"
MATERIAL"CHIP"
VALUE"1.00K"
LOCATION"R9B6"
WATTAGE"1/16W";
"B"
$PN"2"34;
"A"
$PN"1"15;
%"RES"
"1","(-4650,2900)","0","mstr_discrete","I38";
;
CDS_SEC"1"
SEC_TYPE"0402"
SEC"1"
BOM_COST"SM_THERM"
ROOM"TEMP_SENSORS"
CDS_LOCATION"R1E10"
CDS_LIB"mstr_discrete"
PACK_TYPE"0402"
LOCATION"R1E10"
PART_NUMBER"G21796-026"
TOLERANCE"1%"
MATERIAL"CHIP"
VALUE"1.00K"
WATTAGE"1/16W";
"B"
$PN"2"39;
"A"
$PN"1"6;
%"CAP_A"
"1","(-7700,4350)","0","dev_discrete","I39";
;
SEC"1"
SEC_TYPE"0402V"
CDS_SEC"1"
BOM_COST"SM_THERM"
CDS_LOCATION"C9B7"
ROOM"TEMP_SENSORS"
CDS_LIB"dev_discrete"
MATERIAL"X7R"
VOLTAGE"16V"
PACK_TYPE"0402V"
TOLERANCE"10%"
VALUE"0.1UF"
PART_NUMBER"A36096-030"
LOCATION"C9B7";
"B"
$PN"2"9;
"A"
$PN"1"12;
%"CAP_A"
"1","(-7700,3675)","0","dev_discrete","I41";
;
SEC"1"
SEC_TYPE"0402V"
CDS_SEC"1"
BOM_COST"SM_THERM"
CDS_LOCATION"C9R14"
ROOM"TEMP_SENSORS"
CDS_LIB"dev_discrete"
VOLTAGE"16V"
TOLERANCE"10%"
VALUE"0.1UF"
LOCATION"C9R14"
MATERIAL"X7R"
PART_NUMBER"A36096-030"
PACK_TYPE"0402V";
"B"
$PN"2"7;
"A"
$PN"1"13;
%"CAP_A"
"1","(-1425,2150)","0","dev_discrete","I42";
;
BOM_COST"SM_THERM"
SEC_TYPE"0402V"
SEC"1"
ROOM"TEMP_SENSORS"
CDS_SEC"1"
CDS_LOCATION"C9R13"
CDS_LIB"dev_discrete"
LOCATION"C9R13"
VALUE"0.1UF"
TOLERANCE"10%"
VOLTAGE"16V"
MATERIAL"X7R"
PART_NUMBER"A36096-030"
PACK_TYPE"0402V";
"B"
$PN"2"8;
"A"
$PN"1"16;
%"GND"
"1","(-7700,3350)","0","mstr_symbols","I45";
;
SIZE"1B"
VOLTAGE"0.0V"
CDS_LIB"mstr_symbols"
BODY_TYPE"PLUMBING"
HDL_POWER"GND";
"A\NAC"7;
%"GND"
"1","(-1425,1825)","0","mstr_symbols","I46";
;
CDS_LIB"mstr_symbols"
HDL_POWER"GND"
VOLTAGE"0.0V"
SIZE"1B"
BODY_TYPE"PLUMBING";
"A\NAC"8;
%"GND"
"1","(-7700,4100)","0","mstr_symbols","I47";
;
CDS_LIB"mstr_symbols"
HDL_POWER"GND"
SIZE"1B"
VOLTAGE"0.0V"
BODY_TYPE"PLUMBING";
"A\NAC"9;
%"AT24C64"
"1","(-2700,1650)","0","mstr_memory","I49";
;
CDS_SEC"1"
SEC"1"
BOM_COST"SM_THERM"
SEC_TYPE"SOICLF"
PACK_TYPE"SOICLF"
ROOM"TEMP_SENSORS"
CDS_LIB"mstr_memory"
CDS_LOCATION"U8D4"
POWER_GROUP"VCC=P3V3_STBY;GND=GND;"
LOCATION"U8D4"
MATERIAL"IC"
PART_NUMBER"C47049-001";
"SDA"
$PN"5"24;
"WP"
$PN"7"27;
"SCL"
$PN"6"28;
"A0"
$PN"1"11;
"A1"
$PN"2"11;
"A2"
$PN"3"29;
%"RES"
"1","(-5150,4450)","0","mstr_discrete","I5";
;
CDS_SEC"1"
BOM_COST"SM_THERM"
SEC_TYPE"0402"
SEC"1"
ROOM"TEMP_SENSORS"
CDS_LIB"mstr_discrete"
CDS_LOCATION"R9B5"
PACK_TYPE"0402"
TOLERANCE"1%"
LOCATION"R9B5"
PART_NUMBER"G21796-047"
MATERIAL"CHIP"
VALUE"49.9"
WATTAGE"1/16W";
"B"
$PN"2"33;
"A"
$PN"1"35;
%"RES"
"2","(-3500,1300)","0","mstr_discrete","I50";
;
CDS_SEC"1"
SEC_TYPE"0402"
BOM_COST"SM_THERM"
ROOM"TEMP_SENSORS"
CDS_LOCATION"R8D27"
SEC"1"
CDS_LIB"mstr_discrete"
LOCATION"R8D27"
PART_NUMBER"G21796-026"
VALUE"1.00K"
WATTAGE"1/16W"
TOLERANCE"1%"
PACK_TYPE"0402"
MATERIAL"CHIP";
"A"
$PN"1"27;
"B"
$PN"2"10;
%"GND"
"1","(-3500,1050)","0","mstr_symbols","I52";
;
HDL_POWER"GND"
CDS_LIB"mstr_symbols"
SIZE"1B"
VOLTAGE"0.0V"
BODY_TYPE"PLUMBING";
"A\NAC"10;
%"GND"
"1","(-3075,1050)","0","mstr_symbols","I55";
;
SIZE"1B"
CDS_LIB"mstr_symbols"
HDL_POWER"GND"
VOLTAGE"0.0V"
BODY_TYPE"PLUMBING";
"A\NAC"11;
%"P3V3_STBY"
"1","(-7700,4650)","0","mstr_symbols","I56";
;
SIZE"1B"
CDS_LIB"mstr_symbols"
VOLTAGE"3.3V"
BODY_TYPE"PLUMBING"
HDL_POWER"P3V3_STBY";
"G\NAC"12;
%"P3V3_STBY"
"1","(-7700,3950)","0","mstr_symbols","I57";
;
SIZE"1B"
VOLTAGE"3.3V"
CDS_LIB"mstr_symbols"
BODY_TYPE"PLUMBING"
HDL_POWER"P3V3_STBY";
"G\NAC"13;
%"RES"
"1","(-6725,1450)","0","mstr_discrete","I58";
;
BOM_COST"SM_CONTROLLER"
SKU"B"
ROOM"SMBUS"
PACK_TYPE"0402"
CDS_SEC"1"
$SEC"1"
CDS_LOCATION"R9G15"
CDS_LIB"mstr_discrete"
WATTAGE"1/16W"
PART_NUMBER"G21796-173"
MATERIAL"CHIP"
TOLERANCE"1%"
LOCATION"R9G15"
VALUE"20.0";
"B"
$PN"2"44;
"A"
$PN"1"47;
%"RES"
"1","(-5150,4775)","0","mstr_discrete","I6";
;
CDS_SEC"1"
SEC_TYPE"0402"
BOM_COST"SM_THERM"
SEC"1"
ROOM"TEMP_SENSORS"
CDS_LOCATION"R9B4"
CDS_LIB"mstr_discrete"
PACK_TYPE"0402"
LOCATION"R9B4"
PART_NUMBER"G21796-047"
TOLERANCE"1%"
MATERIAL"CHIP"
WATTAGE"1/16W"
VALUE"49.9";
"B"
$PN"2"31;
"A"
$PN"1"36;
%"CAP"
"1","(-4850,4625)","0","mstr_discrete","I7";
;
CDS_SEC"1"
SEC_TYPE"0402LF"
BOM_COST"SM_THERM"
SEC"1"
ROOM"TEMP_SENSORS"
CDS_LOCATION"C1M4"
CDS_LIB"mstr_discrete"
LOCATION"C1M4"
VALUE"47.0PF"
VOLTAGE"50V"
PART_NUMBER"A36095-025"
PACK_TYPE"0402LF"
MATERIAL"EMPTY"
TOLERANCE"5%";
"A"
$PN"1"31;
"B"
$PN"2"33;
%"RES"
"2","(-3350,1975)","0","mstr_discrete","I70";
;
CDS_SEC"1"
ROOM"TEMP_SENSORS"
CDS_LOCATION"R8D28"
SEC"1"
BOM_COST"SM_THERM"
SEC_TYPE"0402"
CDS_LIB"mstr_discrete"
VALUE"1.00K"
LOCATION"R8D28"
PART_NUMBER"G21796-026"
WATTAGE"1/16W"
MATERIAL"CHIP"
PACK_TYPE"0402"
TOLERANCE"1%";
"A"
$PN"1"14;
"B"
$PN"2"29;
%"P3V3_STBY"
"1","(-3350,2200)","0","mstr_symbols","I71";
;
SIZE"1B"
BODY_TYPE"PLUMBING"
VOLTAGE"3.3V"
CDS_LIB"mstr_symbols"
HDL_POWER"P3V3_STBY";
"G\NAC"14;
%"P3V3_STBY"
"1","(-6250,4450)","0","mstr_symbols","I72";
;
VOLTAGE"3.3V"
CDS_LIB"mstr_symbols"
SIZE"1B"
BODY_TYPE"PLUMBING"
HDL_POWER"P3V3_STBY";
"G\NAC"15;
%"P3V3_STBY"
"1","(-1425,2400)","0","mstr_symbols","I73";
;
BODY_TYPE"PLUMBING"
SIZE"1B"
CDS_LIB"mstr_symbols"
VOLTAGE"3.3V"
HDL_POWER"P3V3_STBY";
"G\NAC"16;
%"RES"
"1","(-2650,4450)","0","mstr_discrete","I74";
;
CDS_SEC"1"
BOM_COST"SM_THERM"
SEC_TYPE"0402"
SEC"1"
ROOM"TEMP_SENSORS"
CDS_LOCATION"R1M8"
CDS_LIB"mstr_discrete"
PACK_TYPE"0402"
PART_NUMBER"G21796-173"
MATERIAL"CHIP"
LOCATION"R1M8"
TOLERANCE"1%"
VALUE"20.0"
WATTAGE"1/16W";
"B"
$PN"2"19;
"A"
$PN"1"22;
%"RES"
"1","(-2300,3000)","0","mstr_discrete","I75";
;
CDS_SEC"1"
SEC_TYPE"0402"
BOM_COST"SM_THERM"
SEC"1"
ROOM"TEMP_SENSORS"
CDS_LOCATION"R9R7"
CDS_LIB"mstr_discrete"
PACK_TYPE"0402"
PART_NUMBER"G21796-173"
LOCATION"R9R7"
TOLERANCE"1%"
MATERIAL"CHIP"
VALUE"20.0"
WATTAGE"1/16W";
"B"
$PN"2"19;
"A"
$PN"1"26;
%"RES"
"1","(-2625,3050)","0","mstr_discrete","I76";
;
CDS_SEC"1"
SEC_TYPE"0402"
BOM_COST"SM_THERM"
SEC"1"
CDS_LOCATION"R9R8"
ROOM"TEMP_SENSORS"
CDS_LIB"mstr_discrete"
LOCATION"R9R8"
PART_NUMBER"G21796-173"
PACK_TYPE"0402"
MATERIAL"CHIP"
WATTAGE"1/16W"
TOLERANCE"1%"
VALUE"20.0";
"B"
$PN"2"20;
"A"
$PN"1"25;
%"RES"
"1","(-6725,1325)","0","mstr_discrete","I77";
;
SKU"B"
BOM_COST"SM_CONTROLLER"
ROOM"SMBUS"
PACK_TYPE"0402"
CDS_SEC"1"
$SEC"1"
CDS_LIB"mstr_discrete"
CDS_LOCATION"R9G14"
WATTAGE"1/16W"
PART_NUMBER"G21796-173"
MATERIAL"CHIP"
TOLERANCE"1%"
LOCATION"R9G14"
VALUE"20.0";
"B"
$PN"2"43;
"A"
$PN"1"48;
%"RES"
"1","(-6725,1150)","0","mstr_discrete","I78";
;
BOM_COST"SM_CONTROLLER"
PACK_TYPE"0402"
SKU"B"
ROOM"SMBUS"
CDS_SEC"1"
$SEC"1"
CDS_LOCATION"R1U31"
CDS_LIB"mstr_discrete"
WATTAGE"1/16W"
PART_NUMBER"G21796-173"
TOLERANCE"1%"
MATERIAL"CHIP"
LOCATION"R1U31"
VALUE"20.0";
"B"
$PN"2"45;
"A"
$PN"1"49;
%"RES"
"1","(-6725,1025)","0","mstr_discrete","I79";
;
SKU"B"
BOM_COST"SM_CONTROLLER"
ROOM"SMBUS"
CDS_SEC"1"
$SEC"1"
CDS_LIB"mstr_discrete"
CDS_LOCATION"R1U25"
PACK_TYPE"0402"
WATTAGE"1/16W"
LOCATION"R1U25"
PART_NUMBER"G21796-173"
VALUE"20.0"
TOLERANCE"1%"
MATERIAL"CHIP";
"B"
$PN"2"46;
"A"
$PN"1"50;
%"RES"
"1","(-2950,4500)","0","mstr_discrete","I8";
;
CDS_SEC"1"
BOM_COST"SM_THERM"
SEC_TYPE"0402"
SEC"1"
ROOM"TEMP_SENSORS"
CDS_LIB"mstr_discrete"
CDS_LOCATION"R1M9"
PACK_TYPE"0402"
PART_NUMBER"G21796-173"
LOCATION"R1M9"
TOLERANCE"1%"
MATERIAL"CHIP"
VALUE"20.0"
WATTAGE"1/16W";
"B"
$PN"2"20;
"A"
$PN"1"21;
%"RES"
"2","(-6075,1950)","0","mstr_discrete","I80";
;
CDS_SEC"1"
BOM_COST"SM_CONTROLLER"
ROOM"SMBUS"
SEC_TYPE"0402"
SEC"1"
CDS_LOCATION"R2U38"
CDS_LIB"mstr_discrete"
LOCATION"R2U38"
VALUE"665"
PART_NUMBER"G21796-235"
WATTAGE"1/16W"
MATERIAL"CHIP"
TOLERANCE"1.0%"
PACK_TYPE"0402";
"A"
$PN"1"17;
"B"
$PN"2"43;
%"P3V3_STBY"
"1","(-6075,2200)","0","mstr_symbols","I81";
;
SIZE"1B"
CDS_LIB"mstr_symbols"
VOLTAGE"3.3V"
BODY_TYPE"PLUMBING"
HDL_POWER"P3V3_STBY";
"G\NAC"17;
%"P3V3_STBY"
"1","(-6425,2200)","0","mstr_symbols","I82";
;
SIZE"1B"
BODY_TYPE"PLUMBING"
CDS_LIB"mstr_symbols"
VOLTAGE"3.3V"
HDL_POWER"P3V3_STBY";
"G\NAC"18;
%"RES"
"2","(-6425,1950)","0","mstr_discrete","I83";
;
CDS_SEC"1"
ROOM"SMBUS"
CDS_LOCATION"R2U39"
SEC"1"
SEC_TYPE"0402"
BOM_COST"SM_CONTROLLER"
CDS_LIB"mstr_discrete"
PART_NUMBER"G21796-235"
LOCATION"R2U39"
VALUE"665"
WATTAGE"1/16W"
MATERIAL"CHIP"
PACK_TYPE"0402"
TOLERANCE"1.0%";
"A"
$PN"1"18;
"B"
$PN"2"44;
%"RES"
"1","(-3975,1550)","0","mstr_discrete","I84";
;
CDS_SEC"1"
BOM_COST"SM_THERM"
SEC_TYPE"0402"
ROOM"TEMP_SENSORS"
CDS_LIB"mstr_discrete"
SEC"1"
CDS_LOCATION"R8D24"
PART_NUMBER"G21796-173"
LOCATION"R8D24"
MATERIAL"CHIP"
PACK_TYPE"0402"
TOLERANCE"1%"
VALUE"20.0"
WATTAGE"1/16W";
"B"
$PN"2"28;
"A"
$PN"1"30;
%"RES"
"1","(-1525,1550)","0","mstr_discrete","I85";
;
CDS_LIB"mstr_discrete"
BOM_COST"SM_THERM"
CDS_SEC"1"
$SEC"1"
CDS_LOCATION"R8D23"
ROOM"TEMP_SENSORS"
PACK_TYPE"0402"
TOLERANCE"1%"
MATERIAL"CHIP"
LOCATION"R8D23"
PART_NUMBER"G21796-173"
VALUE"20.0"
WATTAGE"1/16W";
"B"
$PN"2"23;
"A"
$PN"1"24;
END.
